(kicad_pcb
	(version 20260206)
	(generator "pcbnew")
	(generator_version "10.0")
	(general
		(thickness 1.6)
		(legacy_teardrops no)
	)
	(paper "A4")
	(title_block
		(title "Bryce Canyon_F.DPB_16315-1-OCP.brd")
		(comment 1 "Bryce Canyon / footprints 1764-1770 of 2223")
	)
	(layers
		(0 "F.Cu" signal "TOP")
		(4 "In1.Cu" signal "L2GND")
		(6 "In2.Cu" signal "L3")
		(8 "In3.Cu" signal "L4GND")
		(10 "In4.Cu" signal "L5")
		(12 "In5.Cu" signal "L6VCC")
		(14 "In6.Cu" signal "L7VCC")
		(16 "In7.Cu" signal "L8")
		(18 "In8.Cu" signal "L9GND")
		(20 "In9.Cu" signal "L10")
		(22 "In10.Cu" signal "L11GND")
		(2 "B.Cu" signal "BOTTOM")
		(9 "F.Adhes" user "F.Adhesive")
		(11 "B.Adhes" user "B.Adhesive")
		(13 "F.Paste" user "Package Geometry/Pastemask Top")
		(15 "B.Paste" user "Package Geometry/Pastemask Bottom")
		(5 "F.SilkS" user "Ref Des/Silkscreen Top")
		(7 "B.SilkS" user "Ref Des/Silkscreen Bottom")
		(1 "F.Mask" user "Board Geometry/Soldermask Top")
		(3 "B.Mask" user "Board Geometry/Soldermask Bottom")
		(17 "Dwgs.User" user "User.Drawings")
		(19 "Cmts.User" user "User.Comments")
		(21 "Eco1.User" user "User.Eco1")
		(23 "Eco2.User" user "User.Eco2")
		(25 "Edge.Cuts" user "Board Geometry/Outline")
		(27 "Margin" user)
		(31 "F.CrtYd" user "Package Geometry/Place Bound Top")
		(29 "B.CrtYd" user "Package Geometry/Place Bound Bottom")
		(35 "F.Fab" user "Ref Des/Assembly Top")
		(33 "B.Fab" user "Ref Des/Assembly Bottom")
	)
	(footprint ""
		(layer "F.Cu")
		(at 38.059614 -298.219368)
		(property "Reference" "Q288"
			(at 0 0 0)
			(layer "F.SilkS")
			(hide yes)
			(effects
				(font
					(size 1.27 1.27)
				)
			)
		)
		(property "Value" "SSM3K324R-GP"
			(at 0.127 -8.9662 0)
			(unlocked yes)
			(layer "F.Fab")
			(hide yes)
			(effects
				(font
					(size 1.016 1.016)
					(thickness 0.1524)
				)
			)
		)
		(property "Device Type" "SOT23DGS2D4H35"
			(at 0.127 -10.4902 0)
			(unlocked yes)
			(layer "F.Fab")
			(hide yes)
			(effects
				(font
					(size 1.016 1.016)
					(thickness 0.1524)
				)
			)
		)
		(duplicate_pad_numbers_are_jumpers no)
		(fp_line
			(start -1.651 -1.778)
			(end -1.651 1.778)
			(stroke
				(width 0.1524)
				(type default)
			)
			(layer "F.SilkS")
		)
		(fp_line
			(start -1.651 1.778)
			(end 1.651 1.778)
			(stroke
				(width 0.1524)
				(type default)
			)
			(layer "F.SilkS")
		)
		(fp_line
			(start 1.651 -1.778)
			(end -1.651 -1.778)
			(stroke
				(width 0.1524)
				(type default)
			)
			(layer "F.SilkS")
		)
		(fp_line
			(start 1.651 1.778)
			(end 1.651 -1.778)
			(stroke
				(width 0.1524)
				(type default)
			)
			(layer "F.SilkS")
		)
		(fp_poly
			(pts
				(xy -1.778 1.8796) (xy -1.778 -1.8796) (xy 1.778 -1.8796) (xy 1.778 1.8796)
			)
			(stroke
				(width 0)
				(type default)
			)
			(fill no)
			(layer "F.CrtYd")
		)
		(fp_poly
			(pts
				(xy -1.778 1.8796) (xy -1.778 -1.8796) (xy 1.778 -1.8796) (xy 1.778 1.8796)
			)
			(stroke
				(width 0)
				(type default)
			)
			(fill no)
			(layer "F.Fab")
		)
		(pad "D" smd custom
			(at 0 -0.9525)
			(size 0.1905 0.1905)
			(layers "F.Cu" "F.Mask" "F.Paste")
			(net "DRV_ACT_25_N")
			(options
				(clearance outline)
				(anchor circle)
			)
			(primitives
				(gr_poly
					(pts
						(arc
							(start -0.1778 0.5715)
							(mid -0.321484 0.511984)
							(end -0.381 0.3683)
						)
						(arc
							(start -0.381 -0.3683)
							(mid -0.321484 -0.511984)
							(end -0.1778 -0.5715)
						)
						(arc
							(start 0.1778 -0.5715)
							(mid 0.321484 -0.511984)
							(end 0.381 -0.3683)
						)
						(arc
							(start 0.381 0.3683)
							(mid 0.321484 0.511984)
							(end 0.1778 0.5715)
						)
					)
					(width 0)
					(fill yes)
				)
			)
		)
		(pad "G" smd custom
			(at -0.98425 0.9525)
			(size 0.1905 0.1905)
			(layers "F.Cu" "F.Mask" "F.Paste")
			(net "DRIVE_B_25_ACT")
			(options
				(clearance outline)
				(anchor circle)
			)
			(primitives
				(gr_poly
					(pts
						(arc
							(start -0.1778 0.5715)
							(mid -0.321484 0.511984)
							(end -0.381 0.3683)
						)
						(arc
							(start -0.381 -0.3683)
							(mid -0.321484 -0.511984)
							(end -0.1778 -0.5715)
						)
						(arc
							(start 0.1778 -0.5715)
							(mid 0.321484 -0.511984)
							(end 0.381 -0.3683)
						)
						(arc
							(start 0.381 0.3683)
							(mid 0.321484 0.511984)
							(end 0.1778 0.5715)
						)
					)
					(width 0)
					(fill yes)
				)
			)
		)
		(pad "S" smd custom
			(at 0.98425 0.9525)
			(size 0.1905 0.1905)
			(layers "F.Cu" "F.Mask" "F.Paste")
			(net "GND")
			(options
				(clearance outline)
				(anchor circle)
			)
			(primitives
				(gr_poly
					(pts
						(arc
							(start -0.1778 0.5715)
							(mid -0.321484 0.511984)
							(end -0.381 0.3683)
						)
						(arc
							(start -0.381 -0.3683)
							(mid -0.321484 -0.511984)
							(end -0.1778 -0.5715)
						)
						(arc
							(start 0.1778 -0.5715)
							(mid 0.321484 -0.511984)
							(end 0.381 -0.3683)
						)
						(arc
							(start 0.381 0.3683)
							(mid 0.321484 0.511984)
							(end 0.1778 0.5715)
						)
					)
					(width 0)
					(fill yes)
				)
			)
		)
	)
	(footprint ""
		(layer "F.Cu")
		(at 267.174726 -134.995666 -90)
		(property "Reference" "TP201"
			(at 0 0 270)
			(layer "F.SilkS")
			(hide yes)
			(effects
				(font
					(size 1.27 1.27)
				)
			)
		)
		(property "Value" "TPAD32-GP"
			(at -0.0508 -1.6764 270)
			(unlocked yes)
			(layer "F.Fab")
			(hide yes)
			(effects
				(font
					(size 1.016 1.016)
					(thickness 0.1524)
				)
			)
		)
		(property "Device Type" "TPAD32"
			(at -0.0508 -3.2004 270)
			(unlocked yes)
			(layer "F.Fab")
			(hide yes)
			(effects
				(font
					(size 1.016 1.016)
					(thickness 0.1524)
				)
			)
		)
		(duplicate_pad_numbers_are_jumpers no)
		(fp_poly
			(pts
				(arc
					(start 0 -0.4064)
					(mid 0 0.4064)
					(end 0 -0.4064)
				)
			)
			(stroke
				(width 0)
				(type default)
			)
			(fill no)
			(layer "F.CrtYd")
		)
		(fp_poly
			(pts
				(arc
					(start 0 -0.7112)
					(mid 0 0.7112)
					(end 0 -0.7112)
				)
			)
			(stroke
				(width 0)
				(type default)
			)
			(fill no)
			(layer "F.Fab")
		)
		(pad "1" smd circle
			(at 0 0 270)
			(size 0.8128 0.8128)
			(layers "F.Cu" "F.Mask" "F.Paste")
			(net "TP_PCIE_COMP_B_CLK_1_DN")
		)
	)
	(footprint ""
		(layer "F.Cu")
		(at 14.842998 -53.482494 -90)
		(property "Reference" "R697"
			(at 0 0 270)
			(layer "F.SilkS")
			(hide yes)
			(effects
				(font
					(size 1.27 1.27)
				)
			)
		)
		(property "Value" "300KR2F-GP"
			(at 0.064008 -3.993896 270)
			(unlocked yes)
			(layer "F.Fab")
			(hide yes)
			(effects
				(font
					(size 1.016 1.016)
					(thickness 0.1524)
				)
			)
		)
		(property "Device Type" "R402H16"
			(at 0.064008 -5.517896 270)
			(unlocked yes)
			(layer "F.Fab")
			(hide yes)
			(effects
				(font
					(size 1.016 1.016)
					(thickness 0.1524)
				)
			)
		)
		(duplicate_pad_numbers_are_jumpers no)
		(fp_line
			(start -0.508 -0.9398)
			(end -0.508 0.9398)
			(stroke
				(width 0.1524)
				(type default)
			)
			(layer "F.SilkS")
		)
		(fp_line
			(start 0.508 -0.9398)
			(end -0.508 -0.9398)
			(stroke
				(width 0.1524)
				(type default)
			)
			(layer "F.SilkS")
		)
		(fp_rect
			(start -0.508 0.9398)
			(end 0.508 -0.9398)
			(stroke
				(width 0)
				(type default)
			)
			(fill no)
			(layer "F.CrtYd")
		)
		(fp_rect
			(start -0.508 0.9398)
			(end 0.508 -0.9398)
			(stroke
				(width 0)
				(type default)
			)
			(fill no)
			(layer "F.Fab")
		)
		(pad "1" smd custom
			(at 0 -0.4445 270)
			(size 0.1397 0.1397)
			(layers "F.Cu" "F.Mask" "F.Paste")
			(net "SW_HDD_N24")
			(options
				(clearance outline)
				(anchor circle)
			)
			(primitives
				(gr_poly
					(pts
						(arc
							(start -0.1778 -0.2794)
							(mid -0.249642 -0.249642)
							(end -0.2794 -0.1778)
						)
						(arc
							(start -0.2794 0.1778)
							(mid -0.249642 0.249642)
							(end -0.1778 0.2794)
						)
						(arc
							(start 0.1778 0.2794)
							(mid 0.249642 0.249642)
							(end 0.2794 0.1778)
						)
						(arc
							(start 0.2794 -0.1778)
							(mid 0.249642 -0.249642)
							(end 0.1778 -0.2794)
						)
					)
					(width 0)
					(fill yes)
				)
			)
		)
		(pad "2" smd custom
			(at 0 0.4445 270)
			(size 0.1397 0.1397)
			(layers "F.Cu" "F.Mask" "F.Paste")
			(net "P12V_A")
			(options
				(clearance outline)
				(anchor circle)
			)
			(primitives
				(gr_poly
					(pts
						(arc
							(start -0.1778 -0.2794)
							(mid -0.249642 -0.249642)
							(end -0.2794 -0.1778)
						)
						(arc
							(start -0.2794 0.1778)
							(mid -0.249642 0.249642)
							(end -0.1778 0.2794)
						)
						(arc
							(start 0.1778 0.2794)
							(mid 0.249642 0.249642)
							(end 0.2794 0.1778)
						)
						(arc
							(start 0.2794 -0.1778)
							(mid 0.249642 -0.249642)
							(end 0.1778 -0.2794)
						)
					)
					(width 0)
					(fill yes)
				)
			)
		)
	)
	(footprint ""
		(layer "F.Cu")
		(at 105.740962 -127.78867 180)
		(property "Reference" "Q278"
			(at 0 0 180)
			(layer "F.SilkS")
			(hide yes)
			(effects
				(font
					(size 1.27 1.27)
				)
			)
		)
		(property "Value" "SSM3K324R-GP"
			(at 0.127 -8.9662 180)
			(unlocked yes)
			(layer "F.Fab")
			(hide yes)
			(effects
				(font
					(size 1.016 1.016)
					(thickness 0.1524)
				)
			)
		)
		(property "Device Type" "SOT23DGS2D4H35"
			(at 0.127 -10.4902 180)
			(unlocked yes)
			(layer "F.Fab")
			(hide yes)
			(effects
				(font
					(size 1.016 1.016)
					(thickness 0.1524)
				)
			)
		)
		(duplicate_pad_numbers_are_jumpers no)
		(fp_line
			(start 1.651 1.778)
			(end 1.651 -1.778)
			(stroke
				(width 0.1524)
				(type default)
			)
			(layer "F.SilkS")
		)
		(fp_line
			(start 1.651 -1.778)
			(end -1.651 -1.778)
			(stroke
				(width 0.1524)
				(type default)
			)
			(layer "F.SilkS")
		)
		(fp_line
			(start -1.651 1.778)
			(end 1.651 1.778)
			(stroke
				(width 0.1524)
				(type default)
			)
			(layer "F.SilkS")
		)
		(fp_line
			(start -1.651 -1.778)
			(end -1.651 1.778)
			(stroke
				(width 0.1524)
				(type default)
			)
			(layer "F.SilkS")
		)
		(fp_poly
			(pts
				(xy -1.778 1.8796) (xy -1.778 -1.8796) (xy 1.778 -1.8796) (xy 1.778 1.8796)
			)
			(stroke
				(width 0)
				(type default)
			)
			(fill no)
			(layer "F.CrtYd")
		)
		(fp_poly
			(pts
				(xy -1.778 1.8796) (xy -1.778 -1.8796) (xy 1.778 -1.8796) (xy 1.778 1.8796)
			)
			(stroke
				(width 0)
				(type default)
			)
			(fill no)
			(layer "F.Fab")
		)
		(pad "D" smd custom
			(at 0 -0.9525 180)
			(size 0.1905 0.1905)
			(layers "F.Cu" "F.Mask" "F.Paste")
			(net "DRV_ACT_15_N")
			(options
				(clearance outline)
				(anchor circle)
			)
			(primitives
				(gr_poly
					(pts
						(arc
							(start -0.1778 0.5715)
							(mid -0.321484 0.511984)
							(end -0.381 0.3683)
						)
						(arc
							(start -0.381 -0.3683)
							(mid -0.321484 -0.511984)
							(end -0.1778 -0.5715)
						)
						(arc
							(start 0.1778 -0.5715)
							(mid 0.321484 -0.511984)
							(end 0.381 -0.3683)
						)
						(arc
							(start 0.381 0.3683)
							(mid 0.321484 0.511984)
							(end 0.1778 0.5715)
						)
					)
					(width 0)
					(fill yes)
				)
			)
		)
		(pad "G" smd custom
			(at -0.98425 0.9525 180)
			(size 0.1905 0.1905)
			(layers "F.Cu" "F.Mask" "F.Paste")
			(net "DRIVE_A_15_ACT")
			(options
				(clearance outline)
				(anchor circle)
			)
			(primitives
				(gr_poly
					(pts
						(arc
							(start -0.1778 0.5715)
							(mid -0.321484 0.511984)
							(end -0.381 0.3683)
						)
						(arc
							(start -0.381 -0.3683)
							(mid -0.321484 -0.511984)
							(end -0.1778 -0.5715)
						)
						(arc
							(start 0.1778 -0.5715)
							(mid 0.321484 -0.511984)
							(end 0.381 -0.3683)
						)
						(arc
							(start 0.381 0.3683)
							(mid 0.321484 0.511984)
							(end 0.1778 0.5715)
						)
					)
					(width 0)
					(fill yes)
				)
			)
		)
		(pad "S" smd custom
			(at 0.98425 0.9525 180)
			(size 0.1905 0.1905)
			(layers "F.Cu" "F.Mask" "F.Paste")
			(net "GND")
			(options
				(clearance outline)
				(anchor circle)
			)
			(primitives
				(gr_poly
					(pts
						(arc
							(start -0.1778 0.5715)
							(mid -0.321484 0.511984)
							(end -0.381 0.3683)
						)
						(arc
							(start -0.381 -0.3683)
							(mid -0.321484 -0.511984)
							(end -0.1778 -0.5715)
						)
						(arc
							(start 0.1778 -0.5715)
							(mid 0.321484 -0.511984)
							(end 0.381 -0.3683)
						)
						(arc
							(start 0.381 0.3683)
							(mid 0.321484 0.511984)
							(end 0.1778 0.5715)
						)
					)
					(width 0)
					(fill yes)
				)
			)
		)
	)
	(footprint ""
		(layer "F.Cu")
		(at 468.329518 -46.01845 -90)
		(property "Reference" "R952"
			(at 0 0 270)
			(layer "F.SilkS")
			(hide yes)
			(effects
				(font
					(size 1.27 1.27)
				)
			)
		)
		(property "Value" "0R2J-2-GP"
			(at 0.064008 -3.993896 270)
			(unlocked yes)
			(layer "F.Fab")
			(hide yes)
			(effects
				(font
					(size 1.016 1.016)
					(thickness 0.1524)
				)
			)
		)
		(property "Device Type" "R402H16"
			(at 0.064008 -5.517896 270)
			(unlocked yes)
			(layer "F.Fab")
			(hide yes)
			(effects
				(font
					(size 1.016 1.016)
					(thickness 0.1524)
				)
			)
		)
		(duplicate_pad_numbers_are_jumpers no)
		(fp_line
			(start -0.508 -0.9398)
			(end -0.508 0.9398)
			(stroke
				(width 0.1524)
				(type default)
			)
			(layer "F.SilkS")
		)
		(fp_line
			(start 0.508 -0.9398)
			(end -0.508 -0.9398)
			(stroke
				(width 0.1524)
				(type default)
			)
			(layer "F.SilkS")
		)
		(fp_rect
			(start -0.508 0.9398)
			(end 0.508 -0.9398)
			(stroke
				(width 0)
				(type default)
			)
			(fill no)
			(layer "F.CrtYd")
		)
		(fp_rect
			(start -0.508 0.9398)
			(end 0.508 -0.9398)
			(stroke
				(width 0)
				(type default)
			)
			(fill no)
			(layer "F.Fab")
		)
		(pad "1" smd custom
			(at 0 -0.4445 270)
			(size 0.1397 0.1397)
			(layers "F.Cu" "F.Mask" "F.Paste")
			(net "SW_HDD_G35")
			(options
				(clearance outline)
				(anchor circle)
			)
			(primitives
				(gr_poly
					(pts
						(arc
							(start -0.1778 -0.2794)
							(mid -0.249642 -0.249642)
							(end -0.2794 -0.1778)
						)
						(arc
							(start -0.2794 0.1778)
							(mid -0.249642 0.249642)
							(end -0.1778 0.2794)
						)
						(arc
							(start 0.1778 0.2794)
							(mid 0.249642 0.249642)
							(end 0.2794 0.1778)
						)
						(arc
							(start 0.2794 -0.1778)
							(mid 0.249642 -0.249642)
							(end 0.1778 -0.2794)
						)
					)
					(width 0)
					(fill yes)
				)
			)
		)
		(pad "2" smd custom
			(at 0 0.4445 270)
			(size 0.1397 0.1397)
			(layers "F.Cu" "F.Mask" "F.Paste")
			(net "SW_HDD_R35")
			(options
				(clearance outline)
				(anchor circle)
			)
			(primitives
				(gr_poly
					(pts
						(arc
							(start -0.1778 -0.2794)
							(mid -0.249642 -0.249642)
							(end -0.2794 -0.1778)
						)
						(arc
							(start -0.2794 0.1778)
							(mid -0.249642 0.249642)
							(end -0.1778 0.2794)
						)
						(arc
							(start 0.1778 0.2794)
							(mid 0.249642 0.249642)
							(end 0.2794 0.1778)
						)
						(arc
							(start 0.2794 -0.1778)
							(mid 0.249642 -0.249642)
							(end 0.1778 -0.2794)
						)
					)
					(width 0)
					(fill yes)
				)
			)
		)
	)
	(footprint ""
		(layer "F.Cu")
		(at 51.980846 -292.778942 -90)
		(property "Reference" "C53"
			(at 0 0 270)
			(layer "F.SilkS")
			(hide yes)
			(effects
				(font
					(size 1.27 1.27)
				)
			)
		)
		(property "Value" "SC1U16V3KX-5GP"
			(at 0 -2.8194 270)
			(unlocked yes)
			(layer "F.Fab")
			(hide yes)
			(effects
				(font
					(size 1.016 1.016)
					(thickness 0.1524)
				)
			)
		)
		(property "Device Type" "C603H36"
			(at 0 -4.3434 270)
			(unlocked yes)
			(layer "F.Fab")
			(hide yes)
			(effects
				(font
					(size 1.016 1.016)
					(thickness 0.1524)
				)
			)
		)
		(duplicate_pad_numbers_are_jumpers no)
		(fp_line
			(start 0.508 0)
			(end -0.508 0)
			(stroke
				(width 0.2032)
				(type default)
			)
			(layer "F.SilkS")
		)
		(fp_rect
			(start -0.5842 1.3335)
			(end 0.5842 -1.3335)
			(stroke
				(width 0)
				(type default)
			)
			(fill no)
			(layer "F.CrtYd")
		)
		(fp_rect
			(start -0.5842 1.3335)
			(end 0.5842 -1.3335)
			(stroke
				(width 0)
				(type default)
			)
			(fill no)
			(layer "F.Fab")
		)
		(pad "1" smd custom
			(at 0 -0.762 270)
			(size 0.2159 0.2159)
			(layers "F.Cu" "F.Mask" "F.Paste")
			(net "P5V_HDD1")
			(options
				(clearance outline)
				(anchor circle)
			)
			(primitives
				(gr_poly
					(pts
						(arc
							(start -0.3302 -0.4318)
							(mid -0.402042 -0.402042)
							(end -0.4318 -0.3302)
						)
						(arc
							(start -0.4318 0.3302)
							(mid -0.402042 0.402042)
							(end -0.3302 0.4318)
						)
						(arc
							(start 0.3302 0.4318)
							(mid 0.402042 0.402042)
							(end 0.4318 0.3302)
						)
						(arc
							(start 0.4318 -0.3302)
							(mid 0.402042 -0.402042)
							(end 0.3302 -0.4318)
						)
					)
					(width 0)
					(fill yes)
				)
			)
		)
		(pad "2" smd custom
			(at 0 0.762 270)
			(size 0.2159 0.2159)
			(layers "F.Cu" "F.Mask" "F.Paste")
			(net "GND")
			(options
				(clearance outline)
				(anchor circle)
			)
			(primitives
				(gr_poly
					(pts
						(arc
							(start -0.3302 -0.4318)
							(mid -0.402042 -0.402042)
							(end -0.4318 -0.3302)
						)
						(arc
							(start -0.4318 0.3302)
							(mid -0.402042 0.402042)
							(end -0.3302 0.4318)
						)
						(arc
							(start 0.3302 0.4318)
							(mid 0.402042 0.402042)
							(end 0.4318 0.3302)
						)
						(arc
							(start 0.4318 -0.3302)
							(mid 0.402042 -0.402042)
							(end 0.3302 -0.4318)
						)
					)
					(width 0)
					(fill yes)
				)
			)
		)
	)
	(footprint ""
		(layer "F.Cu")
		(at 46.342046 -45.633894 90)
		(property "Reference" "R719"
			(at 0 0 90)
			(layer "F.SilkS")
			(hide yes)
			(effects
				(font
					(size 1.27 1.27)
				)
			)
		)
		(property "Value" "4K7R2J-2-GP"
			(at 0.064008 -3.993896 90)
			(unlocked yes)
			(layer "F.Fab")
			(hide yes)
			(effects
				(font
					(size 1.016 1.016)
					(thickness 0.1524)
				)
			)
		)
		(property "Device Type" "R402H16"
			(at 0.064008 -5.517896 90)
			(unlocked yes)
			(layer "F.Fab")
			(hide yes)
			(effects
				(font
					(size 1.016 1.016)
					(thickness 0.1524)
				)
			)
		)
		(duplicate_pad_numbers_are_jumpers no)
		(fp_line
			(start 0.508 -0.9398)
			(end -0.508 -0.9398)
			(stroke
				(width 0.1524)
				(type default)
			)
			(layer "F.SilkS")
		)
		(fp_line
			(start -0.508 -0.9398)
			(end -0.508 0.9398)
			(stroke
				(width 0.1524)
				(type default)
			)
			(layer "F.SilkS")
		)
		(fp_rect
			(start -0.508 0.9398)
			(end 0.508 -0.9398)
			(stroke
				(width 0)
				(type default)
			)
			(fill no)
			(layer "F.CrtYd")
		)
		(fp_rect
			(start -0.508 0.9398)
			(end 0.508 -0.9398)
			(stroke
				(width 0)
				(type default)
			)
			(fill no)
			(layer "F.Fab")
		)
		(pad "1" smd custom
			(at 0 -0.4445 90)
			(size 0.1397 0.1397)
			(layers "F.Cu" "F.Mask" "F.Paste")
			(net "P12V_A")
			(options
				(clearance outline)
				(anchor circle)
			)
			(primitives
				(gr_poly
					(pts
						(arc
							(start -0.1778 -0.2794)
							(mid -0.249642 -0.249642)
							(end -0.2794 -0.1778)
						)
						(arc
							(start -0.2794 0.1778)
							(mid -0.249642 0.249642)
							(end -0.1778 0.2794)
						)
						(arc
							(start 0.1778 0.2794)
							(mid 0.249642 0.249642)
							(end 0.2794 0.1778)
						)
						(arc
							(start 0.2794 -0.1778)
							(mid 0.249642 -0.249642)
							(end 0.1778 -0.2794)
						)
					)
					(width 0)
					(fill yes)
				)
			)
		)
		(pad "2" smd custom
			(at 0 0.4445 90)
			(size 0.1397 0.1397)
			(layers "F.Cu" "F.Mask" "F.Paste")
			(net "SW_HDD_R25")
			(options
				(clearance outline)
				(anchor circle)
			)
			(primitives
				(gr_poly
					(pts
						(arc
							(start -0.1778 -0.2794)
							(mid -0.249642 -0.249642)
							(end -0.2794 -0.1778)
						)
						(arc
							(start -0.2794 0.1778)
							(mid -0.249642 0.249642)
							(end -0.1778 0.2794)
						)
						(arc
							(start 0.1778 0.2794)
							(mid 0.249642 0.249642)
							(end 0.2794 0.1778)
						)
						(arc
							(start 0.2794 -0.1778)
							(mid 0.249642 -0.249642)
							(end 0.1778 -0.2794)
						)
					)
					(width 0)
					(fill yes)
				)
			)
		)
	)
)
